(kicad_pcb
	(version 20241229)
	(generator "pcbnew")
	(generator_version "9.0")
	(general
		(thickness 1.552)
		(legacy_teardrops no)
	)
	(paper "A4")
	(title_block
		(date "2023-07-25")
		(rev "1.1.4")
		(comment 9 "footprints 271-274 of 379")
	)
	(layers
		(0 "F.Cu" signal)
		(4 "In1.Cu" signal)
		(6 "In2.Cu" signal)
		(8 "In3.Cu" signal)
		(10 "In4.Cu" signal)
		(12 "In5.Cu" signal)
		(14 "In6.Cu" signal)
		(2 "B.Cu" signal)
		(9 "F.Adhes" user "F.Adhesive")
		(11 "B.Adhes" user "B.Adhesive")
		(13 "F.Paste" user)
		(15 "B.Paste" user)
		(5 "F.SilkS" user "F.Silkscreen")
		(7 "B.SilkS" user "B.Silkscreen")
		(1 "F.Mask" user)
		(3 "B.Mask" user)
		(17 "Dwgs.User" user "User.Drawings")
		(19 "Cmts.User" user "User.Comments")
		(21 "Eco1.User" user "User.Eco1")
		(23 "Eco2.User" user "User.Eco2")
		(25 "Edge.Cuts" user)
		(27 "Margin" user)
		(31 "F.CrtYd" user "F.Courtyard")
		(29 "B.CrtYd" user "B.Courtyard")
		(35 "F.Fab" user)
		(33 "B.Fab" user)
	)
	(footprint "antmicro-footprints:R_Array_4x0402"
		(layer "B.Cu")
		(at 121.56 57.44 180)
		(property "Reference" "R48"
			(at -1.07 1 0)
			(layer "B.SilkS")
			(effects
				(font
					(size 0.65 0.65)
					(thickness 0.15)
				)
				(justify left bottom mirror)
			)
		)
		(property "Value" "R_4x51R_0402_array"
			(at -1.5 -2 0)
			(layer "B.Fab")
			(hide yes)
			(effects
				(font
					(size 0.7 0.7)
					(thickness 0.15)
				)
				(justify left bottom mirror)
			)
		)
		(property "Datasheet" "http://industrial.panasonic.com/cdbs/www-data/pdf/AOC0000/AOC0000C14.pdf"
			(at 0 0 180)
			(layer "F.Fab")
			(hide yes)
			(effects
				(font
					(size 1.27 1.27)
					(thickness 0.15)
				)
			)
		)
		(property "Description" "Fixed Network Resistor, 51 ohm, Isolated, 4 Resistors, 0804 [2010 Metric], Convex, ± 5%"
			(at 0 0 180)
			(layer "F.Fab")
			(hide yes)
			(effects
				(font
					(size 1.27 1.27)
					(thickness 0.15)
				)
			)
		)
		(property "Author" "Antmicro"
			(at 243.12 114.88 0)
			(layer "B.Fab")
			(hide yes)
			(effects
				(font
					(size 1 1)
					(thickness 0.15)
				)
				(justify mirror)
			)
		)
		(property "License" "Apache-2.0"
			(at 243.12 114.88 0)
			(layer "B.Fab")
			(hide yes)
			(effects
				(font
					(size 1 1)
					(thickness 0.15)
				)
				(justify mirror)
			)
		)
		(property "MPN" "EXB28V510JX"
			(at 243.12 114.88 0)
			(layer "B.Fab")
			(hide yes)
			(effects
				(font
					(size 1 1)
					(thickness 0.15)
				)
				(justify mirror)
			)
		)
		(property "Manufacturer" "Panasonic"
			(at 243.12 114.88 0)
			(layer "B.Fab")
			(hide yes)
			(effects
				(font
					(size 1 1)
					(thickness 0.15)
				)
				(justify mirror)
			)
		)
		(property "Val" "R_4x51R_0402"
			(at 243.12 114.88 0)
			(layer "B.Fab")
			(hide yes)
			(effects
				(font
					(size 1 1)
					(thickness 0.15)
				)
				(justify mirror)
			)
		)
		(sheetname "/DDR3/")
		(sheetfile "ddr3.kicad_sch")
		(attr smd)
		(fp_line
			(start 1.167 -0.498)
			(end 1.167 0.5)
			(stroke
				(width 0.15)
				(type solid)
			)
			(layer "B.SilkS")
		)
		(fp_line
			(start -1.17 0.5)
			(end -1.17 -0.498)
			(stroke
				(width 0.15)
				(type solid)
			)
			(layer "B.SilkS")
		)
		(fp_rect
			(start -1.2 0.9)
			(end 1.2 -0.9)
			(stroke
				(width 0.05)
				(type solid)
			)
			(fill no)
			(layer "B.CrtYd")
		)
		(fp_line
			(start 0.998 0.5)
			(end 0.998 -0.498)
			(stroke
				(width 0.15)
				(type solid)
			)
			(layer "B.Fab")
		)
		(fp_line
			(start 0.998 -0.498)
			(end -1 -0.498)
			(stroke
				(width 0.15)
				(type solid)
			)
			(layer "B.Fab")
		)
		(fp_line
			(start -1 0.5)
			(end 0.998 0.5)
			(stroke
				(width 0.15)
				(type solid)
			)
			(layer "B.Fab")
		)
		(fp_line
			(start -1 -0.498)
			(end -1 0.5)
			(stroke
				(width 0.15)
				(type solid)
			)
			(layer "B.Fab")
		)
		(pad "1" smd roundrect
			(at -0.802 -0.45 180)
			(size 0.4 0.5)
			(layers "B.Cu" "B.Mask" "B.Paste")
			(roundrect_rratio 0.25)
			(net 151 "/DDR3/DDR3_A4")
			(pinfunction "R1.1")
			(pintype "passive")
		)
		(pad "2" smd roundrect
			(at -0.272 -0.45 180)
			(size 0.4 0.5)
			(layers "B.Cu" "B.Mask" "B.Paste")
			(roundrect_rratio 0.25)
			(net 154 "/DDR3/DDR3_A11")
			(pinfunction "R2.1")
			(pintype "passive")
		)
		(pad "3" smd roundrect
			(at 0.27 -0.45 180)
			(size 0.4 0.5)
			(layers "B.Cu" "B.Mask" "B.Paste")
			(roundrect_rratio 0.25)
			(net 148 "/DDR3/DDR3_A6")
			(pinfunction "R3.1")
			(pintype "passive")
		)
		(pad "4" smd roundrect
			(at 0.8 -0.45 180)
			(size 0.4 0.5)
			(layers "B.Cu" "B.Mask" "B.Paste")
			(roundrect_rratio 0.25)
			(net 155 "/DDR3/DDR3_A8")
			(pinfunction "R4.1")
			(pintype "passive")
		)
		(pad "5" smd roundrect
			(at 0.8 0.452 180)
			(size 0.4 0.5)
			(layers "B.Cu" "B.Mask" "B.Paste")
			(roundrect_rratio 0.25)
			(net 6 "Vtt")
			(pinfunction "R4.2")
			(pintype "passive")
		)
		(pad "6" smd roundrect
			(at 0.27 0.452 180)
			(size 0.4 0.5)
			(layers "B.Cu" "B.Mask" "B.Paste")
			(roundrect_rratio 0.25)
			(net 6 "Vtt")
			(pinfunction "R3.2")
			(pintype "passive")
		)
		(pad "7" smd roundrect
			(at -0.272 0.452 180)
			(size 0.4 0.5)
			(layers "B.Cu" "B.Mask" "B.Paste")
			(roundrect_rratio 0.25)
			(net 6 "Vtt")
			(pinfunction "R2.2")
			(pintype "passive")
		)
		(pad "8" smd roundrect
			(at -0.802 0.452 180)
			(size 0.4 0.5)
			(layers "B.Cu" "B.Mask" "B.Paste")
			(roundrect_rratio 0.25)
			(net 6 "Vtt")
			(pinfunction "R1.2")
			(pintype "passive")
		)
	)
	(footprint "antmicro-footprints:C_0603_1608Metric"
		(layer "B.Cu")
		(at 127.72 100.54 90)
		(descr "Capacitor SMD 0603")
		(tags "capacitor 0603")
		(property "Reference" "C89"
			(at -3.35 0.31 90)
			(layer "B.SilkS")
			(effects
				(font
					(size 0.65 0.65)
					(thickness 0.15)
				)
				(justify right bottom mirror)
			)
		)
		(property "Value" "C_10u_0603"
			(at 0 -1.6 90)
			(layer "B.Fab")
			(hide yes)
			(effects
				(font
					(size 0.7 0.7)
					(thickness 0.15)
				)
				(justify right bottom mirror)
			)
		)
		(property "Datasheet" "https://www.murata.com/products/productdetail?partno=GRM188R61A106KE69%23"
			(at 0 0 90)
			(layer "F.Fab")
			(hide yes)
			(effects
				(font
					(size 1.27 1.27)
					(thickness 0.15)
				)
			)
		)
		(property "Description" "SMD Multilayer Ceramic Capacitor, 10 µF, 10 V, 0603 [1608 Metric], ± 10%, X5R, GRM Series"
			(at 0 0 90)
			(layer "F.Fab")
			(hide yes)
			(effects
				(font
					(size 1.27 1.27)
					(thickness 0.15)
				)
			)
		)
		(property "Author" "Antmicro"
			(at 228.26 -27.18 0)
			(layer "B.Fab")
			(hide yes)
			(effects
				(font
					(size 1 1)
					(thickness 0.15)
				)
				(justify mirror)
			)
		)
		(property "License" "Apache-2.0"
			(at 228.26 -27.18 0)
			(layer "B.Fab")
			(hide yes)
			(effects
				(font
					(size 1 1)
					(thickness 0.15)
				)
				(justify mirror)
			)
		)
		(property "MPN" "GRM188R61A106KE69D"
			(at 228.26 -27.18 0)
			(layer "B.Fab")
			(hide yes)
			(effects
				(font
					(size 1 1)
					(thickness 0.15)
				)
				(justify mirror)
			)
		)
		(property "Manufacturer" "Murata"
			(at 228.26 -27.18 0)
			(layer "B.Fab")
			(hide yes)
			(effects
				(font
					(size 1 1)
					(thickness 0.15)
				)
				(justify mirror)
			)
		)
		(property "Val" "10u"
			(at 228.26 -27.18 0)
			(layer "B.Fab")
			(hide yes)
			(effects
				(font
					(size 1 1)
					(thickness 0.15)
				)
				(justify mirror)
			)
		)
		(property "Voltage" ""
			(at 228.26 -27.18 0)
			(layer "B.Fab")
			(hide yes)
			(effects
				(font
					(size 1 1)
					(thickness 0.15)
				)
				(justify mirror)
			)
		)
		(property "Dielectric" "template_dielectric"
			(at 0 0 90)
			(unlocked yes)
			(layer "B.Fab")
			(hide yes)
			(effects
				(font
					(size 1 1)
					(thickness 0.15)
				)
				(justify mirror)
			)
		)
		(sheetname "/FPGA Power/")
		(sheetfile "FPGA_Power.kicad_sch")
		(attr smd)
		(fp_line
			(start -0.15 -0.4)
			(end 0.15 -0.4)
			(stroke
				(width 0.15)
				(type solid)
			)
			(layer "B.SilkS")
		)
		(fp_line
			(start -0.15 0.4)
			(end 0.15 0.4)
			(stroke
				(width 0.15)
				(type solid)
			)
			(layer "B.SilkS")
		)
		(fp_rect
			(start -1.25 0.65)
			(end 1.25 -0.65)
			(stroke
				(width 0.05)
				(type solid)
			)
			(fill no)
			(layer "B.CrtYd")
		)
		(fp_rect
			(start -0.8 0.4)
			(end 0.8 -0.4)
			(stroke
				(width 0.15)
				(type solid)
			)
			(fill no)
			(layer "B.Fab")
		)
		(fp_text user "Author: Antmicro"
			(at -1.682 -4.894 270)
			(layer "B.Fab")
			(effects
				(font
					(size 0.7 0.7)
					(thickness 0.15)
				)
				(justify left bottom mirror)
			)
		)
		(fp_text user "${REFERENCE}"
			(at -1.682 -3.895 270)
			(layer "B.Fab")
			(effects
				(font
					(size 0.7 0.7)
					(thickness 0.15)
				)
				(justify left bottom mirror)
			)
		)
		(fp_text user "License: Apache-2.0"
			(at -1.682 -5.895 270)
			(layer "B.Fab")
			(effects
				(font
					(size 0.7 0.7)
					(thickness 0.15)
				)
				(justify left bottom mirror)
			)
		)
		(pad "1" smd roundrect
			(at -0.7 0 90)
			(size 0.8 1)
			(layers "B.Cu" "B.Mask" "B.Paste")
			(roundrect_rratio 0.2)
			(net 1 "GND")
			(pintype "passive")
		)
		(pad "2" smd roundrect
			(at 0.7 0 90)
			(size 0.8 1)
			(layers "B.Cu" "B.Mask" "B.Paste")
			(roundrect_rratio 0.2)
			(net 11 "/FPGA Power/VCC_DPHY")
			(pintype "passive")
		)
	)
	(footprint "antmicro-footprints:PinHeader_1x6_P2.54mm_SMD_Horizontal"
		(layer "B.Cu")
		(at 158.7415 119.14)
		(property "Reference" "J10"
			(at 6.7885 -7.7 180)
			(layer "B.SilkS")
			(effects
				(font
					(size 0.7 0.7)
					(thickness 0.15)
				)
				(justify left bottom mirror)
			)
		)
		(property "Value" "PinHeader_1x6_P2.54mm_SMD_Horizontal"
			(at 0 -8.8 180)
			(layer "B.Fab")
			(effects
				(font
					(size 0.7 0.7)
					(thickness 0.15)
				)
				(justify left bottom mirror)
			)
		)
		(property "Datasheet" "https://www.mouser.com/datasheet/2/527/tsm-2854655.pdf"
			(at 0 0 0)
			(layer "F.Fab")
			(hide yes)
			(effects
				(font
					(size 1.27 1.27)
					(thickness 0.15)
				)
			)
		)
		(property "Description" "Connector Header Surface Mount, Right Angle 6 position 0.100\" (2.54mm)"
			(at 0 0 0)
			(layer "F.Fab")
			(hide yes)
			(effects
				(font
					(size 1.27 1.27)
					(thickness 0.15)
				)
			)
		)
		(property "Author" "Antmicro"
			(at 0 0 0)
			(layer "B.Fab")
			(hide yes)
			(effects
				(font
					(size 1 1)
					(thickness 0.15)
				)
				(justify mirror)
			)
		)
		(property "License" "Apache-2.0"
			(at 0 0 0)
			(layer "B.Fab")
			(hide yes)
			(effects
				(font
					(size 1 1)
					(thickness 0.15)
				)
				(justify mirror)
			)
		)
		(property "MPN" "TSM-106-01-T-SH"
			(at 0 0 0)
			(layer "B.Fab")
			(hide yes)
			(effects
				(font
					(size 1 1)
					(thickness 0.15)
				)
				(justify mirror)
			)
		)
		(property "Manufacturer" "Samtec"
			(at 0 0 0)
			(layer "B.Fab")
			(hide yes)
			(effects
				(font
					(size 1 1)
					(thickness 0.15)
				)
				(justify mirror)
			)
		)
		(sheetname "/Peripherals/")
		(sheetfile "peripherals.kicad_sch")
		(attr smd exclude_from_pos_files exclude_from_bom dnp)
		(fp_line
			(start -7.62 -1.904)
			(end -7.62 0.635)
			(stroke
				(width 0.15)
				(type solid)
			)
			(layer "B.SilkS")
		)
		(fp_line
			(start 7.618 -1.904)
			(end -7.62 -1.904)
			(stroke
				(width 0.15)
				(type solid)
			)
			(layer "B.SilkS")
		)
		(fp_line
			(start 7.618 0.635)
			(end -7.62 0.635)
			(stroke
				(width 0.15)
				(type solid)
			)
			(layer "B.SilkS")
		)
		(fp_line
			(start 7.618 0.635)
			(end 7.618 -1.904)
			(stroke
				(width 0.15)
				(type solid)
			)
			(layer "B.SilkS")
		)
		(fp_circle
			(center -7.321 -5.913)
			(end -7.271 -5.913)
			(stroke
				(width 0.15)
				(type solid)
			)
			(fill yes)
			(layer "B.SilkS")
		)
		(fp_rect
			(start -8 6.8)
			(end 8 -7.8)
			(stroke
				(width 0.05)
				(type solid)
			)
			(fill no)
			(layer "B.CrtYd")
		)
		(fp_line
			(start -7.62 -6.75)
			(end -6.895 -7.475)
			(stroke
				(width 0.15)
				(type solid)
			)
			(layer "B.Fab")
		)
		(fp_line
			(start -7.62 -1.904)
			(end -7.62 -6.75)
			(stroke
				(width 0.15)
				(type solid)
			)
			(layer "B.Fab")
		)
		(fp_line
			(start -7.62 -1.904)
			(end -7.62 6.476)
			(stroke
				(width 0.15)
				(type solid)
			)
			(layer "B.Fab")
		)
		(fp_line
			(start -7.62 0.635)
			(end 7.618 0.635)
			(stroke
				(width 0.15)
				(type solid)
			)
			(layer "B.Fab")
		)
		(fp_line
			(start -7.62 6.476)
			(end 7.618 6.476)
			(stroke
				(width 0.15)
				(type solid)
			)
			(layer "B.Fab")
		)
		(fp_line
			(start -6.895 -7.475)
			(end 7.618 -7.475)
			(stroke
				(width 0.15)
				(type solid)
			)
			(layer "B.Fab")
		)
		(fp_line
			(start 7.618 -7.475)
			(end 7.618 -1.904)
			(stroke
				(width 0.15)
				(type solid)
			)
			(layer "B.Fab")
		)
		(fp_line
			(start 7.618 -1.904)
			(end -7.62 -1.904)
			(stroke
				(width 0.15)
				(type solid)
			)
			(layer "B.Fab")
		)
		(fp_line
			(start 7.618 6.476)
			(end 7.618 -1.904)
			(stroke
				(width 0.15)
				(type solid)
			)
			(layer "B.Fab")
		)
		(fp_text user "License: Apache-2.0"
			(at -8.93 -13.199 180)
			(layer "B.Fab")
			(effects
				(font
					(size 0.7 0.7)
					(thickness 0.15)
				)
				(justify left bottom mirror)
			)
		)
		(fp_text user "${REFERENCE}"
			(at -8.93 -14.4 180)
			(layer "B.Fab")
			(effects
				(font
					(size 0.7 0.7)
					(thickness 0.15)
				)
				(justify left bottom mirror)
			)
		)
		(fp_text user "Author: Antmicro"
			(at -8.93 -12 180)
			(layer "B.Fab")
			(effects
				(font
					(size 0.7 0.7)
					(thickness 0.15)
				)
				(justify left bottom mirror)
			)
		)
		(pad "1" smd roundrect
			(at -6.351 -5.914)
			(size 1.27 3.18)
			(layers "B.Cu" "B.Mask" "B.Paste")
			(roundrect_rratio 0.25)
			(net 331 "/Peripherals/3V3_MISC")
			(pintype "passive")
		)
		(pad "2" smd roundrect
			(at -3.81 -5.914)
			(size 1.27 3.18)
			(layers "B.Cu" "B.Mask" "B.Paste")
			(roundrect_rratio 0.25)
			(net 332 "GPIO0")
			(pintype "passive")
		)
		(pad "3" smd roundrect
			(at -1.27 -5.914)
			(size 1.27 3.18)
			(layers "B.Cu" "B.Mask" "B.Paste")
			(roundrect_rratio 0.25)
			(net 333 "GPIO1")
			(pintype "passive")
		)
		(pad "4" smd roundrect
			(at 1.267 -5.914)
			(size 1.27 3.18)
			(layers "B.Cu" "B.Mask" "B.Paste")
			(roundrect_rratio 0.25)
			(net 334 "GPIO2")
			(pintype "passive")
		)
		(pad "5" smd roundrect
			(at 3.809 -5.914)
			(size 1.27 3.18)
			(layers "B.Cu" "B.Mask" "B.Paste")
			(roundrect_rratio 0.25)
			(net 335 "GPIO3")
			(pintype "passive")
		)
		(pad "6" smd roundrect
			(at 6.349 -5.914)
			(size 1.27 3.18)
			(layers "B.Cu" "B.Mask" "B.Paste")
			(roundrect_rratio 0.25)
			(net 1 "GND")
			(pintype "passive")
		)
	)
	(footprint "antmicro-footprints:C_0603_1608Metric"
		(layer "B.Cu")
		(at 127.82 80.7)
		(descr "Capacitor SMD 0603")
		(tags "capacitor 0603")
		(property "Reference" "C92"
			(at -3.29 0.44 0)
			(layer "B.SilkS")
			(effects
				(font
					(size 0.65 0.65)
					(thickness 0.15)
				)
				(justify right bottom mirror)
			)
		)
		(property "Value" "C_10u_0603"
			(at 0 -1.6 0)
			(layer "B.Fab")
			(hide yes)
			(effects
				(font
					(size 0.7 0.7)
					(thickness 0.15)
				)
				(justify right bottom mirror)
			)
		)
		(property "Datasheet" "https://www.murata.com/products/productdetail?partno=GRM188R61A106KE69%23"
			(at 0 0 0)
			(layer "F.Fab")
			(hide yes)
			(effects
				(font
					(size 1.27 1.27)
					(thickness 0.15)
				)
			)
		)
		(property "Description" "SMD Multilayer Ceramic Capacitor, 10 µF, 10 V, 0603 [1608 Metric], ± 10%, X5R, GRM Series"
			(at 0 0 0)
			(layer "F.Fab")
			(hide yes)
			(effects
				(font
					(size 1.27 1.27)
					(thickness 0.15)
				)
			)
		)
		(property "Author" "Antmicro"
			(at 0 0 0)
			(layer "B.Fab")
			(hide yes)
			(effects
				(font
					(size 1 1)
					(thickness 0.15)
				)
				(justify mirror)
			)
		)
		(property "License" "Apache-2.0"
			(at 0 0 0)
			(layer "B.Fab")
			(hide yes)
			(effects
				(font
					(size 1 1)
					(thickness 0.15)
				)
				(justify mirror)
			)
		)
		(property "MPN" "GRM188R61A106KE69D"
			(at 0 0 0)
			(layer "B.Fab")
			(hide yes)
			(effects
				(font
					(size 1 1)
					(thickness 0.15)
				)
				(justify mirror)
			)
		)
		(property "Manufacturer" "Murata"
			(at 0 0 0)
			(layer "B.Fab")
			(hide yes)
			(effects
				(font
					(size 1 1)
					(thickness 0.15)
				)
				(justify mirror)
			)
		)
		(property "Val" "10u"
			(at 0 0 0)
			(layer "B.Fab")
			(hide yes)
			(effects
				(font
					(size 1 1)
					(thickness 0.15)
				)
				(justify mirror)
			)
		)
		(property "Voltage" ""
			(at 0 0 0)
			(layer "B.Fab")
			(hide yes)
			(effects
				(font
					(size 1 1)
					(thickness 0.15)
				)
				(justify mirror)
			)
		)
		(property "Dielectric" "template_dielectric"
			(at 0 0 0)
			(unlocked yes)
			(layer "B.Fab")
			(hide yes)
			(effects
				(font
					(size 1 1)
					(thickness 0.15)
				)
				(justify mirror)
			)
		)
		(sheetname "/FPGA Power/")
		(sheetfile "FPGA_Power.kicad_sch")
		(attr smd)
		(fp_line
			(start -0.15 -0.4)
			(end 0.15 -0.4)
			(stroke
				(width 0.15)
				(type solid)
			)
			(layer "B.SilkS")
		)
		(fp_line
			(start -0.15 0.4)
			(end 0.15 0.4)
			(stroke
				(width 0.15)
				(type solid)
			)
			(layer "B.SilkS")
		)
		(fp_rect
			(start -1.25 0.65)
			(end 1.25 -0.65)
			(stroke
				(width 0.05)
				(type solid)
			)
			(fill no)
			(layer "B.CrtYd")
		)
		(fp_rect
			(start -0.8 0.4)
			(end 0.8 -0.4)
			(stroke
				(width 0.15)
				(type solid)
			)
			(fill no)
			(layer "B.Fab")
		)
		(fp_text user "Author: Antmicro"
			(at -1.682 -4.894 180)
			(layer "B.Fab")
			(effects
				(font
					(size 0.7 0.7)
					(thickness 0.15)
				)
				(justify left bottom mirror)
			)
		)
		(fp_text user "${REFERENCE}"
			(at -1.682 -3.895 180)
			(layer "B.Fab")
			(effects
				(font
					(size 0.7 0.7)
					(thickness 0.15)
				)
				(justify left bottom mirror)
			)
		)
		(fp_text user "License: Apache-2.0"
			(at -1.682 -5.895 180)
			(layer "B.Fab")
			(effects
				(font
					(size 0.7 0.7)
					(thickness 0.15)
				)
				(justify left bottom mirror)
			)
		)
		(pad "1" smd roundrect
			(at -0.7 0)
			(size 0.8 1)
			(layers "B.Cu" "B.Mask" "B.Paste")
			(roundrect_rratio 0.2)
			(net 1 "GND")
			(pintype "passive")
		)
		(pad "2" smd roundrect
			(at 0.7 0)
			(size 0.8 1)
			(layers "B.Cu" "B.Mask" "B.Paste")
			(roundrect_rratio 0.2)
			(net 9 "/FPGA Power/VCC_AUX")
			(pintype "passive")
		)
	)
)
